(kicad_pcb
	(version 20260206)
	(generator "pcbnew")
	(generator_version "10.0")
	(general
		(thickness 1.6)
		(legacy_teardrops no)
	)
	(paper "A4")
	(title_block
		(title "04192023_DAF0TMB3IC0_F0TG_MB_C_brd_V02_OCP.brd")
		(comment 1 "Grand Teton / footprint 625 of 8354 (J112), pads 1-74 of 74")
	)
	(layers
		(0 "F.Cu" signal "TOP")
		(4 "In1.Cu" signal "GND")
		(6 "In2.Cu" signal "IN1")
		(8 "In3.Cu" signal "GND1")
		(10 "In4.Cu" signal "IN2")
		(12 "In5.Cu" signal "GND2")
		(14 "In6.Cu" signal "IN3")
		(16 "In7.Cu" signal "GND3")
		(18 "In8.Cu" signal "VCC")
		(20 "In9.Cu" signal "VCC1")
		(22 "In10.Cu" signal "GND4")
		(24 "In11.Cu" signal "IN4")
		(26 "In12.Cu" signal "GND5")
		(28 "In13.Cu" signal "IN5")
		(30 "In14.Cu" signal "GND6")
		(32 "In15.Cu" signal "IN6")
		(34 "In16.Cu" signal "GND7")
		(2 "B.Cu" signal "BOTTOM")
		(9 "F.Adhes" user "F.Adhesive")
		(11 "B.Adhes" user "B.Adhesive")
		(13 "F.Paste" user "Package Geometry/Pastemask Top")
		(15 "B.Paste" user "Package Geometry/Pastemask Bottom")
		(5 "F.SilkS" user "Ref Des/Silkscreen Top")
		(7 "B.SilkS" user "Ref Des/Silkscreen Bottom")
		(1 "F.Mask" user "Board Geometry/Soldermask Top")
		(3 "B.Mask" user "Board Geometry/Soldermask Bottom")
		(17 "Dwgs.User" user "User.Drawings")
		(19 "Cmts.User" user "User.Comments")
		(21 "Eco1.User" user "User.Eco1")
		(23 "Eco2.User" user "User.Eco2")
		(25 "Edge.Cuts" user "Board Geometry/Outline")
		(27 "Margin" user)
		(31 "F.CrtYd" user "Package Geometry/Place Bound Top")
		(29 "B.CrtYd" user "Package Geometry/Place Bound Bottom")
		(35 "F.Fab" user "Ref Des/Assembly Top")
		(33 "B.Fab" user "Ref Des/Assembly Bottom")
	)
	(footprint ""
		(layer "F.Cu")
		(at 58.64987 -440.489848)
		(property "Reference" "J112"
			(at -4.958842 26.716736 90)
			(unlocked yes)
			(layer "F.SilkS")
			(effects
				(font
					(size 0.7874 0.5842)
					(thickness 0.1524)
				)
				(justify left)
			)
		)
		(property "Value" ""
			(at 0 0 0)
			(layer "F.Fab")
			(effects
				(font
					(size 1.27 1.27)
				)
			)
		)
		(duplicate_pad_numbers_are_jumpers no)
		(pad "A1" thru_hole rect
			(at 0 0 180)
			(size 0.766318 0.766318)
			(drill 0.359918)
			(layers "*.Cu" "*.Mask")
			(remove_unused_layers no)
			(net "RST_PERST_2_SWB_BUF_N")
			(clearance 0.0508)
			(thermal_gap 0.0508)
			(padstack
				(mode front_inner_back)
				(layer "Inner"
					(shape circle)
					(size 0.766318 0.766318)
					(clearance 0.0508)
				)
				(layer "B.Cu"
					(shape rect)
					(size 0.766318 0.766318)
					(clearance 0.0508)
				)
			)
		)
		(pad "A2" thru_hole circle
			(at 1.999996 0.199898 180)
			(size 0.906272 0.906272)
			(drill 0.499872)
			(layers "*.Cu" "*.Mask")
			(remove_unused_layers no)
			(net "GND")
			(clearance 0.0508)
			(thermal_gap 0.0508)
		)
		(pad "A3" thru_hole circle
			(at 3.999992 0 180)
			(size 0.766318 0.766318)
			(drill 0.359918)
			(layers "*.Cu" "*.Mask")
			(remove_unused_layers no)
			(net "HGX_DETECT_N_ISO")
			(clearance 0.0508)
			(thermal_gap 0.0508)
		)
		(pad "A4" thru_hole circle
			(at 5.999988 0.199898 180)
			(size 0.906272 0.906272)
			(drill 0.499872)
			(layers "*.Cu" "*.Mask")
			(remove_unused_layers no)
			(net "GND")
			(clearance 0.0508)
			(thermal_gap 0.0508)
		)
		(pad "A5" thru_hole circle
			(at 7.999984 0 180)
			(size 0.766318 0.766318)
			(drill 0.359918)
			(layers "*.Cu" "*.Mask")
			(remove_unused_layers no)
			(net "RST_PERST_1_SWB_BUF_N")
			(clearance 0.0508)
			(thermal_gap 0.0508)
		)
		(pad "A6" thru_hole circle
			(at 9.99998 0.199898 180)
			(size 0.906272 0.906272)
			(drill 0.499872)
			(layers "*.Cu" "*.Mask")
			(remove_unused_layers no)
			(net "GND")
			(clearance 0.0508)
			(thermal_gap 0.0508)
		)
		(pad "A7" thru_hole circle
			(at 11.999976 0 180)
			(size 0.766318 0.766318)
			(drill 0.359918)
			(layers "*.Cu" "*.Mask")
			(remove_unused_layers no)
			(net "PRSNT_SWB_N")
			(clearance 0.0508)
			(thermal_gap 0.0508)
		)
		(pad "A8" thru_hole circle
			(at 13.999972 0.199898 180)
			(size 0.906272 0.906272)
			(drill 0.499872)
			(layers "*.Cu" "*.Mask")
			(remove_unused_layers no)
			(net "GND")
			(clearance 0.0508)
			(thermal_gap 0.0508)
		)
		(pad "B1" thru_hole circle
			(at 0 1.199896 180)
			(size 0.906272 0.906272)
			(drill 0.499872)
			(layers "*.Cu" "*.Mask")
			(remove_unused_layers no)
			(net "GND")
			(clearance 0.0508)
			(thermal_gap 0.0508)
		)
		(pad "B3" thru_hole circle
			(at 3.999992 1.199896 180)
			(size 0.906272 0.906272)
			(drill 0.499872)
			(layers "*.Cu" "*.Mask")
			(remove_unused_layers no)
			(net "GND")
			(clearance 0.0508)
			(thermal_gap 0.0508)
		)
		(pad "B5" thru_hole circle
			(at 7.999984 1.199896 180)
			(size 0.906272 0.906272)
			(drill 0.499872)
			(layers "*.Cu" "*.Mask")
			(remove_unused_layers no)
			(net "GND")
			(clearance 0.0508)
			(thermal_gap 0.0508)
		)
		(pad "B7" thru_hole circle
			(at 11.999976 1.199896 180)
			(size 0.906272 0.906272)
			(drill 0.499872)
			(layers "*.Cu" "*.Mask")
			(remove_unused_layers no)
			(net "GND")
			(clearance 0.0508)
			(thermal_gap 0.0508)
		)
		(pad "D2" thru_hole circle
			(at 1.999996 3.800094 180)
			(size 0.906272 0.906272)
			(drill 0.499872)
			(layers "*.Cu" "*.Mask")
			(remove_unused_layers no)
			(net "GND")
			(clearance 0.0508)
			(thermal_gap 0.0508)
		)
		(pad "D4" thru_hole circle
			(at 5.999988 3.800094 180)
			(size 0.906272 0.906272)
			(drill 0.499872)
			(layers "*.Cu" "*.Mask")
			(remove_unused_layers no)
			(net "GND")
			(clearance 0.0508)
			(thermal_gap 0.0508)
		)
		(pad "D6" thru_hole circle
			(at 9.99998 3.800094 180)
			(size 0.906272 0.906272)
			(drill 0.499872)
			(layers "*.Cu" "*.Mask")
			(remove_unused_layers no)
			(net "GND")
			(clearance 0.0508)
			(thermal_gap 0.0508)
		)
		(pad "D8" thru_hole circle
			(at 13.999972 3.800094 180)
			(size 0.906272 0.906272)
			(drill 0.499872)
			(layers "*.Cu" "*.Mask")
			(remove_unused_layers no)
			(net "GND")
			(clearance 0.0508)
			(thermal_gap 0.0508)
		)
		(pad "E1" thru_hole circle
			(at 0 4.800092 180)
			(size 0.906272 0.906272)
			(drill 0.499872)
			(layers "*.Cu" "*.Mask")
			(remove_unused_layers no)
			(net "GND")
			(clearance 0.0508)
			(thermal_gap 0.0508)
		)
		(pad "E3" thru_hole circle
			(at 3.999992 4.800092 180)
			(size 0.906272 0.906272)
			(drill 0.499872)
			(layers "*.Cu" "*.Mask")
			(remove_unused_layers no)
			(net "GND")
			(clearance 0.0508)
			(thermal_gap 0.0508)
		)
		(pad "E5" thru_hole circle
			(at 7.999984 4.800092 180)
			(size 0.906272 0.906272)
			(drill 0.499872)
			(layers "*.Cu" "*.Mask")
			(remove_unused_layers no)
			(net "GND")
			(clearance 0.0508)
			(thermal_gap 0.0508)
		)
		(pad "E7" thru_hole circle
			(at 11.999976 4.800092 180)
			(size 0.906272 0.906272)
			(drill 0.499872)
			(layers "*.Cu" "*.Mask")
			(remove_unused_layers no)
			(net "GND")
			(clearance 0.0508)
			(thermal_gap 0.0508)
		)
		(pad "G2" thru_hole circle
			(at 1.999996 7.400036 180)
			(size 0.906272 0.906272)
			(drill 0.499872)
			(layers "*.Cu" "*.Mask")
			(remove_unused_layers no)
			(net "GND")
			(clearance 0.0508)
			(thermal_gap 0.0508)
		)
		(pad "G4" thru_hole circle
			(at 5.999988 7.400036 180)
			(size 0.906272 0.906272)
			(drill 0.499872)
			(layers "*.Cu" "*.Mask")
			(remove_unused_layers no)
			(net "GND")
			(clearance 0.0508)
			(thermal_gap 0.0508)
		)
		(pad "G6" thru_hole circle
			(at 9.99998 7.400036 180)
			(size 0.906272 0.906272)
			(drill 0.499872)
			(layers "*.Cu" "*.Mask")
			(remove_unused_layers no)
			(net "GND")
			(clearance 0.0508)
			(thermal_gap 0.0508)
		)
		(pad "G8" thru_hole circle
			(at 13.999972 7.400036 180)
			(size 0.906272 0.906272)
			(drill 0.499872)
			(layers "*.Cu" "*.Mask")
			(remove_unused_layers no)
			(net "GND")
			(clearance 0.0508)
			(thermal_gap 0.0508)
		)
		(pad "H1" thru_hole circle
			(at 0 8.400034 180)
			(size 0.906272 0.906272)
			(drill 0.499872)
			(layers "*.Cu" "*.Mask")
			(remove_unused_layers no)
			(net "GND")
			(clearance 0.0508)
			(thermal_gap 0.0508)
		)
		(pad "H3" thru_hole circle
			(at 3.999992 8.400034 180)
			(size 0.906272 0.906272)
			(drill 0.499872)
			(layers "*.Cu" "*.Mask")
			(remove_unused_layers no)
			(net "GND")
			(clearance 0.0508)
			(thermal_gap 0.0508)
		)
		(pad "H5" thru_hole circle
			(at 7.999984 8.400034 180)
			(size 0.906272 0.906272)
			(drill 0.499872)
			(layers "*.Cu" "*.Mask")
			(remove_unused_layers no)
			(net "GND")
			(clearance 0.0508)
			(thermal_gap 0.0508)
		)
		(pad "H7" thru_hole circle
			(at 11.999976 8.400034 180)
			(size 0.906272 0.906272)
			(drill 0.499872)
			(layers "*.Cu" "*.Mask")
			(remove_unused_layers no)
			(net "GND")
			(clearance 0.0508)
			(thermal_gap 0.0508)
		)
		(pad "J2" thru_hole circle
			(at 1.999996 10.999978 180)
			(size 0.906272 0.906272)
			(drill 0.499872)
			(layers "*.Cu" "*.Mask")
			(remove_unused_layers no)
			(net "GND")
			(clearance 0.0508)
			(thermal_gap 0.0508)
		)
		(pad "J4" thru_hole circle
			(at 5.999988 10.999978 180)
			(size 0.906272 0.906272)
			(drill 0.499872)
			(layers "*.Cu" "*.Mask")
			(remove_unused_layers no)
			(net "GND")
			(clearance 0.0508)
			(thermal_gap 0.0508)
		)
		(pad "J6" thru_hole circle
			(at 9.99998 10.999978 180)
			(size 0.906272 0.906272)
			(drill 0.499872)
			(layers "*.Cu" "*.Mask")
			(remove_unused_layers no)
			(net "GND")
			(clearance 0.0508)
			(thermal_gap 0.0508)
		)
		(pad "J8" thru_hole circle
			(at 13.999972 10.999978 180)
			(size 0.906272 0.906272)
			(drill 0.499872)
			(layers "*.Cu" "*.Mask")
			(remove_unused_layers no)
			(net "GND")
			(clearance 0.0508)
			(thermal_gap 0.0508)
		)
		(pad "K1" thru_hole circle
			(at 0 11.999976 180)
			(size 0.906272 0.906272)
			(drill 0.499872)
			(layers "*.Cu" "*.Mask")
			(remove_unused_layers no)
			(net "GND")
			(clearance 0.0508)
			(thermal_gap 0.0508)
		)
		(pad "K3" thru_hole circle
			(at 3.999992 11.999976 180)
			(size 0.906272 0.906272)
			(drill 0.499872)
			(layers "*.Cu" "*.Mask")
			(remove_unused_layers no)
			(net "GND")
			(clearance 0.0508)
			(thermal_gap 0.0508)
		)
		(pad "K5" thru_hole circle
			(at 7.999984 11.999976 180)
			(size 0.906272 0.906272)
			(drill 0.499872)
			(layers "*.Cu" "*.Mask")
			(remove_unused_layers no)
			(net "GND")
			(clearance 0.0508)
			(thermal_gap 0.0508)
		)
		(pad "K7" thru_hole circle
			(at 11.999976 11.999976 180)
			(size 0.906272 0.906272)
			(drill 0.499872)
			(layers "*.Cu" "*.Mask")
			(remove_unused_layers no)
			(net "GND")
			(clearance 0.0508)
			(thermal_gap 0.0508)
		)
		(pad "M2" thru_hole circle
			(at 1.999996 14.59992 180)
			(size 0.906272 0.906272)
			(drill 0.499872)
			(layers "*.Cu" "*.Mask")
			(remove_unused_layers no)
			(net "GND")
			(clearance 0.0508)
			(thermal_gap 0.0508)
		)
		(pad "M4" thru_hole circle
			(at 5.999988 14.59992 180)
			(size 0.906272 0.906272)
			(drill 0.499872)
			(layers "*.Cu" "*.Mask")
			(remove_unused_layers no)
			(net "GND")
			(clearance 0.0508)
			(thermal_gap 0.0508)
		)
		(pad "M6" thru_hole circle
			(at 9.99998 14.59992 180)
			(size 0.906272 0.906272)
			(drill 0.499872)
			(layers "*.Cu" "*.Mask")
			(remove_unused_layers no)
			(net "GND")
			(clearance 0.0508)
			(thermal_gap 0.0508)
		)
		(pad "M8" thru_hole circle
			(at 13.999972 14.59992 180)
			(size 0.906272 0.906272)
			(drill 0.499872)
			(layers "*.Cu" "*.Mask")
			(remove_unused_layers no)
			(net "GND")
			(clearance 0.0508)
			(thermal_gap 0.0508)
		)
		(pad "N1" thru_hole circle
			(at 0 15.599918 180)
			(size 0.906272 0.906272)
			(drill 0.499872)
			(layers "*.Cu" "*.Mask")
			(remove_unused_layers no)
			(net "GND")
			(clearance 0.0508)
			(thermal_gap 0.0508)
		)
		(pad "N2" thru_hole circle
			(at 1.999996 15.80007 180)
			(size 0.766318 0.766318)
			(drill 0.359918)
			(layers "*.Cu" "*.Mask")
			(remove_unused_layers no)
			(net "NC_J112_N2")
			(clearance 0.0508)
			(thermal_gap 0.0508)
		)
		(pad "N3" thru_hole circle
			(at 3.999992 15.599918 180)
			(size 0.906272 0.906272)
			(drill 0.499872)
			(layers "*.Cu" "*.Mask")
			(remove_unused_layers no)
			(net "GND")
			(clearance 0.0508)
			(thermal_gap 0.0508)
		)
		(pad "N5" thru_hole circle
			(at 7.999984 15.599918 180)
			(size 0.906272 0.906272)
			(drill 0.499872)
			(layers "*.Cu" "*.Mask")
			(remove_unused_layers no)
			(net "GND")
			(clearance 0.0508)
			(thermal_gap 0.0508)
		)
		(pad "N7" thru_hole circle
			(at 11.999976 15.599918 180)
			(size 0.906272 0.906272)
			(drill 0.499872)
			(layers "*.Cu" "*.Mask")
			(remove_unused_layers no)
			(net "GND")
			(clearance 0.0508)
			(thermal_gap 0.0508)
		)
		(pad "O2" thru_hole circle
			(at 1.999996 16.999966 180)
			(size 0.766318 0.766318)
			(drill 0.359918)
			(layers "*.Cu" "*.Mask")
			(remove_unused_layers no)
			(net "NC_J112_O2")
			(clearance 0.0508)
			(thermal_gap 0.0508)
		)
		(pad "O5" thru_hole circle
			(at 7.999984 16.800068 180)
			(size 0.766318 0.766318)
			(drill 0.359918)
			(layers "*.Cu" "*.Mask")
			(remove_unused_layers no)
			(net "NC_J112_O5")
			(clearance 0.0508)
			(thermal_gap 0.0508)
		)
		(pad "P2" thru_hole circle
			(at 1.999996 18.200116 180)
			(size 0.906272 0.906272)
			(drill 0.499872)
			(layers "*.Cu" "*.Mask")
			(remove_unused_layers no)
			(net "GND")
			(clearance 0.0508)
			(thermal_gap 0.0508)
		)
		(pad "P4" thru_hole circle
			(at 5.999988 18.200116 180)
			(size 0.906272 0.906272)
			(drill 0.499872)
			(layers "*.Cu" "*.Mask")
			(remove_unused_layers no)
			(net "GND")
			(clearance 0.0508)
			(thermal_gap 0.0508)
		)
		(pad "P5" thru_hole circle
			(at 7.999984 17.999964 180)
			(size 0.766318 0.766318)
			(drill 0.359918)
			(layers "*.Cu" "*.Mask")
			(remove_unused_layers no)
			(net "NC_J112_P5")
			(clearance 0.0508)
			(thermal_gap 0.0508)
		)
		(pad "P6" thru_hole circle
			(at 9.99998 18.200116 180)
			(size 0.906272 0.906272)
			(drill 0.499872)
			(layers "*.Cu" "*.Mask")
			(remove_unused_layers no)
			(net "GND")
			(clearance 0.0508)
			(thermal_gap 0.0508)
		)
		(pad "P8" thru_hole circle
			(at 13.999972 18.200116 180)
			(size 0.906272 0.906272)
			(drill 0.499872)
			(layers "*.Cu" "*.Mask")
			(remove_unused_layers no)
			(net "GND")
			(clearance 0.0508)
			(thermal_gap 0.0508)
		)
		(pad "Q1" thru_hole circle
			(at 0 19.200114 180)
			(size 0.906272 0.906272)
			(drill 0.499872)
			(layers "*.Cu" "*.Mask")
			(remove_unused_layers no)
			(net "GND")
			(clearance 0.0508)
			(thermal_gap 0.0508)
		)
		(pad "Q3" thru_hole circle
			(at 3.999992 19.200114 180)
			(size 0.906272 0.906272)
			(drill 0.499872)
			(layers "*.Cu" "*.Mask")
			(remove_unused_layers no)
			(net "GND")
			(clearance 0.0508)
			(thermal_gap 0.0508)
		)
		(pad "Q4" thru_hole circle
			(at 5.999988 19.400012 180)
			(size 0.766318 0.766318)
			(drill 0.359918)
			(layers "*.Cu" "*.Mask")
			(remove_unused_layers no)
			(net "SMB_1_BMC_GPU_BUF_SCL")
			(clearance 0.0508)
			(thermal_gap 0.0508)
		)
		(pad "Q5" thru_hole circle
			(at 7.999984 19.200114 180)
			(size 0.906272 0.906272)
			(drill 0.499872)
			(layers "*.Cu" "*.Mask")
			(remove_unused_layers no)
			(net "GND")
			(clearance 0.0508)
			(thermal_gap 0.0508)
		)
		(pad "Q7" thru_hole circle
			(at 11.999976 19.200114 180)
			(size 0.906272 0.906272)
			(drill 0.499872)
			(layers "*.Cu" "*.Mask")
			(remove_unused_layers no)
			(net "GND")
			(clearance 0.0508)
			(thermal_gap 0.0508)
		)
		(pad "R3" thru_hole circle
			(at 3.999992 20.40001 180)
			(size 0.766318 0.766318)
			(drill 0.359918)
			(layers "*.Cu" "*.Mask")
			(remove_unused_layers no)
			(net "SMB_2_BMC_GPU_BUF_SCL")
			(clearance 0.0508)
			(thermal_gap 0.0508)
		)
		(pad "R4" thru_hole circle
			(at 5.999988 20.599908 180)
			(size 0.766318 0.766318)
			(drill 0.359918)
			(layers "*.Cu" "*.Mask")
			(remove_unused_layers no)
			(net "SMB_1_BMC_GPU_BUF_SDA")
			(clearance 0.0508)
			(thermal_gap 0.0508)
		)
		(pad "R5" thru_hole circle
			(at 7.999984 20.40001 180)
			(size 0.766318 0.766318)
			(drill 0.359918)
			(layers "*.Cu" "*.Mask")
			(remove_unused_layers no)
			(net "NC_J112_R5")
			(clearance 0.0508)
			(thermal_gap 0.0508)
		)
		(pad "S2" thru_hole circle
			(at 1.999996 21.800058 180)
			(size 0.906272 0.906272)
			(drill 0.499872)
			(layers "*.Cu" "*.Mask")
			(remove_unused_layers no)
			(net "GND")
			(clearance 0.0508)
			(thermal_gap 0.0508)
		)
		(pad "S3" thru_hole circle
			(at 3.999992 21.599906 180)
			(size 0.766318 0.766318)
			(drill 0.359918)
			(layers "*.Cu" "*.Mask")
			(remove_unused_layers no)
			(net "SMB_2_BMC_GPU_BUF_SDA")
			(clearance 0.0508)
			(thermal_gap 0.0508)
		)
		(pad "S4" thru_hole circle
			(at 5.999988 21.800058 180)
			(size 0.906272 0.906272)
			(drill 0.499872)
			(layers "*.Cu" "*.Mask")
			(remove_unused_layers no)
			(net "GND")
			(clearance 0.0508)
			(thermal_gap 0.0508)
		)
		(pad "S5" thru_hole circle
			(at 7.999984 21.599906 180)
			(size 0.766318 0.766318)
			(drill 0.359918)
			(layers "*.Cu" "*.Mask")
			(remove_unused_layers no)
			(net "NC_J112_S5")
			(clearance 0.0508)
			(thermal_gap 0.0508)
		)
		(pad "S6" thru_hole circle
			(at 9.99998 21.800058 180)
			(size 0.906272 0.906272)
			(drill 0.499872)
			(layers "*.Cu" "*.Mask")
			(remove_unused_layers no)
			(net "GND")
			(clearance 0.0508)
			(thermal_gap 0.0508)
		)
		(pad "S8" thru_hole circle
			(at 13.999972 21.800058 180)
			(size 0.906272 0.906272)
			(drill 0.499872)
			(layers "*.Cu" "*.Mask")
			(remove_unused_layers no)
			(net "GND")
			(clearance 0.0508)
			(thermal_gap 0.0508)
		)
		(pad "T1" thru_hole circle
			(at 0 22.800056 180)
			(size 0.906272 0.906272)
			(drill 0.499872)
			(layers "*.Cu" "*.Mask")
			(remove_unused_layers no)
			(net "GND")
			(clearance 0.0508)
			(thermal_gap 0.0508)
		)
		(pad "T2" thru_hole circle
			(at 1.999996 22.999954 180)
			(size 0.766318 0.766318)
			(drill 0.359918)
			(layers "*.Cu" "*.Mask")
			(remove_unused_layers no)
			(net "GPU_FPGA_READY")
			(clearance 0.0508)
			(thermal_gap 0.0508)
		)
		(pad "T3" thru_hole circle
			(at 3.999992 22.800056 180)
			(size 0.906272 0.906272)
			(drill 0.499872)
			(layers "*.Cu" "*.Mask")
			(remove_unused_layers no)
			(net "GND")
			(clearance 0.0508)
			(thermal_gap 0.0508)
		)
		(pad "T4" thru_hole circle
			(at 5.999988 22.999954 180)
			(size 0.766318 0.766318)
			(drill 0.359918)
			(layers "*.Cu" "*.Mask")
			(remove_unused_layers no)
			(net "GPU_NVS_PWR_BRAKE_N_BUF")
			(clearance 0.0508)
			(thermal_gap 0.0508)
		)
		(pad "T5" thru_hole circle
			(at 7.999984 22.800056 180)
			(size 0.906272 0.906272)
			(drill 0.499872)
			(layers "*.Cu" "*.Mask")
			(remove_unused_layers no)
			(net "GND")
			(clearance 0.0508)
			(thermal_gap 0.0508)
		)
		(pad "T6" thru_hole circle
			(at 9.99998 22.999954 180)
			(size 0.766318 0.766318)
			(drill 0.359918)
			(layers "*.Cu" "*.Mask")
			(remove_unused_layers no)
			(net "GPU_FPGA_THERM_OVERT_N")
			(clearance 0.0508)
			(thermal_gap 0.0508)
		)
		(pad "T7" thru_hole circle
			(at 11.999976 22.800056 180)
			(size 0.906272 0.906272)
			(drill 0.499872)
			(layers "*.Cu" "*.Mask")
			(remove_unused_layers no)
			(net "GND")
			(clearance 0.0508)
			(thermal_gap 0.0508)
		)
		(pad "T8" thru_hole circle
			(at 13.999972 22.999954 180)
			(size 0.766318 0.766318)
			(drill 0.359918)
			(layers "*.Cu" "*.Mask")
			(remove_unused_layers no)
			(net "RST_PERST_0_SWB_BUF_N")
			(clearance 0.0508)
			(thermal_gap 0.0508)
		)
	)
)
